# S9S_MB_2U (Grand Teton) — schematic netlist excerpt (pin names and nets, part order shuffled) for the footprints in the layout excerpt that follows; sources: Cadence DE-HDL packaged netlist, KiCad conversion of 03242023_DA0F0TMBIJ0_F0T_Motherboard_J_brd_V01_OCP.brd

J13  SCONN288_ADR50017P130CC  SCONN288_ADR50017-P130CC IO  pkg DDR288S_1-1VXB  page 94
  VIN_BULK0  = P12V_S3_AUX_CPU0_NVDIMM
  RFU0  = TP_CHG_CPU0_DIMM1_FRU_0
  VIN_MGMT  = P3V3_AUX
  HSCL  = I3C_SPD_DDREFGH_CPU0_LVC1_SCL_4
  HSDA  = I3C_SPD_DDREFGH_CPU0_LVC1_SDA
  VSS0  = GND
  DQ0_A  = M_G_CPU0_SA_DQ<0>
  VSS1  = GND
  DQ1_A  = M_G_CPU0_SA_DQ<1>
  VSS2  = GND
  DQS0_A_T  = M_G_CPU0_SA_DQS_DP<0>
  DQS0_A_C  = M_G_CPU0_SA_DQS_DN<0>
  VSS3  = GND
  DQ4_A  = M_G_CPU0_SA_DQ<4>
  VSS4  = GND
  DQ5_A  = M_G_CPU0_SA_DQ<5>
  VSS5  = GND
  DQ8_A  = M_G_CPU0_SA_DQ<8>
  VSS6  = GND
  DQ9_A  = M_G_CPU0_SA_DQ<9>
  VSS7  = GND
  DQS1_A_T  = M_G_CPU0_SA_DQS_DP<1>
  DQS1_A_C  = M_G_CPU0_SA_DQS_DN<1>
  VSS8  = GND
  DQ12_A  = M_G_CPU0_SA_DQ<12>
  VSS9  = GND
  DQ13_A  = M_G_CPU0_SA_DQ<13>
  VSS10  = GND
  DQ16_A  = M_G_CPU0_SA_DQ<16>
  VSS11  = GND
  DQ17_A  = M_G_CPU0_SA_DQ<17>
  VSS12  = GND
  DQS2_A_T  = M_G_CPU0_SA_DQS_DP<2>
  DQS2_A_C  = M_G_CPU0_SA_DQS_DN<2>
  VSS13  = GND
  DQ20_A  = M_G_CPU0_SA_DQ<20>
  VSS14  = GND
  DQ21_A  = M_G_CPU0_SA_DQ<21>
  VSS15  = GND
  DQ24_A  = M_G_CPU0_SA_DQ<24>
  VSS16  = GND
  DQ25_A  = M_G_CPU0_SA_DQ<25>
  VSS17  = GND
  DQS3_A_T  = M_G_CPU0_SA_DQS_DP<3>
  DQS3_A_C  = M_G_CPU0_SA_DQS_DN<3>
  VSS18  = GND
  DQ28_A  = M_G_CPU0_SA_DQ<28>
  VSS19  = GND
  DQ29_A  = M_G_CPU0_SA_DQ<29>
  VSS20  = GND
  CB0_A  = M_G_CPU0_SA_CB<0>
  VSS21  = GND
  CB1_A  = M_G_CPU0_SA_CB<1>
  VSS22  = GND
  DQS4_A_T  = M_G_CPU0_SA_DQS_DP<4>
  DQS4_A_C  = M_G_CPU0_SA_DQS_DN<4>
  VSS23  = GND
  CB4_A  = M_G_CPU0_SA_CB<4>
  VSS24  = GND
  CB5_A  = M_G_CPU0_SA_CB<5>
  VSS25  = GND
  ALERT_N  = M_G_CPU0_ALERT_N
  VSS26  = GND
  CS0_A_N  = M_G_CPU0_SA_CS_N<0>
  VSS27  = GND
  CA0_A  = M_G_CPU0_SA_CA<0>
  VSS28  = GND
  CA2_A  = M_G_CPU0_SA_CA<2>
  VSS29  = GND
  CA4_A  = M_G_CPU0_SA_CA<4>
  VSS30  = GND
  CA6_A  = M_G_CPU0_SA_CA<6>
  VSS31  = GND
  PAR_A  = M_G_CPU0_SA_PAR
  VSS32  = GND
  CA0_B  = M_G_CPU0_SB_CA<0>
  VSS33  = GND
  CA2_B  = M_G_CPU0_SB_CA<2>
  VSS34  = GND
  CA4_B  = M_G_CPU0_SB_CA<4>
  VSS35  = GND
  CA6_B  = M_G_CPU0_SB_CA<6>
  VSS36  = GND
  CS0_B_N  = M_G_CPU0_SB_CS_N<0>
  VSS37  = GND
  \lbd||rsp_a_n\  = M_G_CPU0_SA_RSP<0>
  \lbs||rsp_b_n\  = M_G_CPU0_SB_RSP<0>
  VSS38  = GND
  CB4_B  = M_G_CPU0_SB_CB<4>
  VSS39  = GND
  CB5_B  = M_G_CPU0_SB_CB<5>
  VSS40  = GND
  \dqs9_b_t||tdqs9_b_t||dbi4_b_n\  = M_G_CPU0_SB_DQS_DP<9>
  \dqs9_b_c||tdqs9_b_c\  = M_G_CPU0_SB_DQS_DN<9>
  VSS41  = GND
  CB0_B  = M_G_CPU0_SB_CB<0>
  VSS42  = GND
  CB1_B  = M_G_CPU0_SB_CB<1>
  VSS43  = GND
  DQ0_B  = M_G_CPU0_SB_DQ<0>
  VSS44  = GND
  DQ1_B  = M_G_CPU0_SB_DQ<1>
  VSS45  = GND
  DQS0_B_T  = M_G_CPU0_SB_DQS_DP<0>
  DQS0_B_C  = M_G_CPU0_SB_DQS_DN<0>
  VSS46  = GND
  DQ4_B  = M_G_CPU0_SB_DQ<4>
  VSS47  = GND
  DQ5_B  = M_G_CPU0_SB_DQ<5>
  VSS48  = GND
  DQ8_B  = M_G_CPU0_SB_DQ<8>
  VSS49  = GND
  DQ9_B  = M_G_CPU0_SB_DQ<9>
  VSS50  = GND
  DQS1_B_T  = M_G_CPU0_SB_DQS_DP<1>
  DQS1_B_C  = M_G_CPU0_SB_DQS_DN<1>
  VSS51  = GND
  DQ12_B  = M_G_CPU0_SB_DQ<12>
  VSS52  = GND
  DQ13_B  = M_G_CPU0_SB_DQ<13>
  VSS53  = GND
  DQ16_B  = M_G_CPU0_SB_DQ<16>
  VSS54  = GND
  DQ17_B  = M_G_CPU0_SB_DQ<17>
  VSS55  = GND
  DQS2_B_T  = M_G_CPU0_SB_DQS_DP<2>
  DQS2_B_C  = M_G_CPU0_SB_DQS_DN<2>
  VSS56  = GND
  DQ20_B  = M_G_CPU0_SB_DQ<20>
  VSS57  = GND
  DQ21_B  = M_G_CPU0_SB_DQ<21>
  VSS58  = GND
  DQ24_B  = M_G_CPU0_SB_DQ<24>
  VSS59  = GND
  DQ25_B  = M_G_CPU0_SB_DQ<25>
  VSS60  = GND
  DQS3_B_T  = M_G_CPU0_SB_DQS_DP<3>
  DQS3_B_C  = M_G_CPU0_SB_DQS_DN<3>
  VSS61  = GND
  DQ28_B  = M_G_CPU0_SB_DQ<28>
  VSS62  = GND
  DQ29_B  = M_G_CPU0_SB_DQ<29>
  VSS63  = GND
  RFU1  = TP_CHG_CPU0_DIMM1_FRU_1
  VIN_BULK1  = P12V_S3_AUX_CPU0_NVDIMM
  VIN_BULK2  = P12V_S3_AUX_CPU0_NVDIMM
  \pwr_good||fail_n\  = PWRGD_CHG_CPU0_DIMM1
  HSA  = PD_CHG_CPU0_DIMM1_SAA
  RFU2  = TP_CHG_CPU0_DIMM1_FRU_2
  RFU3  = TP_CHG_CPU0_DIMM1_FRU_3
  VSS64  = GND
  DQ2_A  = M_G_CPU0_SA_DQ<2>
  VSS65  = GND
  DQ3_A  = M_G_CPU0_SA_DQ<3>
  VSS66  = GND
  \dqs5_a_c||tdqs5_a_c||dqs5_a_t||tdqs5_a_t\  = M_G_CPU0_SA_DQS_DN<5>
  \dqs5_a_t||tdqs5_a_t\  = M_G_CPU0_SA_DQS_DP<5>
  VSS67  = GND
  DQ6_A  = M_G_CPU0_SA_DQ<6>
  VSS68  = GND
  DQ7_A  = M_G_CPU0_SA_DQ<7>
  VSS69  = GND
  DQ10_A  = M_G_CPU0_SA_DQ<10>
  VSS70  = GND
  DQ11_A  = M_G_CPU0_SA_DQ<11>
  VSS71  = GND
  \dqs6_a_c||tdqs6_a_c||dqs6_a_t||tdqs6_a_t\  = M_G_CPU0_SA_DQS_DN<6>
  \dqs6_a_t||tdqs6_a_t\  = M_G_CPU0_SA_DQS_DP<6>
  VSS72  = GND
  DQ14_A  = M_G_CPU0_SA_DQ<14>
  VSS73  = GND
  DQ15_A  = M_G_CPU0_SA_DQ<15>
  VSS74  = GND
  DQ18_A  = M_G_CPU0_SA_DQ<18>
  VSS75  = GND
  DQ19_A  = M_G_CPU0_SA_DQ<19>
  VSS76  = GND
  \dqs7_a_c||tdqs7_a_c\  = M_G_CPU0_SA_DQS_DN<7>
  \dqs7_a_t||tdqs7_a_t\  = M_G_CPU0_SA_DQS_DP<7>
  VSS77  = GND
  DQ22_A  = M_G_CPU0_SA_DQ<22>
  VSS78  = GND
  DQ23_A  = M_G_CPU0_SA_DQ<23>
  VSS79  = GND
  DQ26_A  = M_G_CPU0_SA_DQ<26>
  VSS80  = GND
  DQ27_A  = M_G_CPU0_SA_DQ<27>
  VSS81  = GND
  \dqs8_a_c||tdqs8_a_c\  = M_G_CPU0_SA_DQS_DN<8>
  \dqs8_a_t||tdqs8_a_t\  = M_G_CPU0_SA_DQS_DP<8>
  VSS82  = GND
  DQ30_A  = M_G_CPU0_SA_DQ<30>
  VSS83  = GND
  DQ31_A  = M_G_CPU0_SA_DQ<31>
  VSS84  = GND
  CB2_A  = M_G_CPU0_SA_CB<2>
  VSS85  = GND
  CB3_A  = M_G_CPU0_SA_CB<3>
  VSS86  = GND
  \dqs9_a_c||tdqs9_a_c\  = M_G_CPU0_SA_DQS_DN<9>
  \dqs9_a_t||tdqs9_a_t\  = M_G_CPU0_SA_DQS_DP<9>
  VSS87  = GND
  CB6_A  = M_G_CPU0_SA_CB<6>
  VSS88  = GND
  CB7_A  = M_G_CPU0_SA_CB<7>
  VSS89  = GND
  RESET_N  = RST_M_GH_CPU0_FPGA_N
  VSS90  = GND
  CS1_A_N  = M_G_CPU0_SA_CS_N<1>
  VSS91  = GND
  CA1_A  = M_G_CPU0_SA_CA<1>
  VSS92  = GND
  CA3_A  = M_G_CPU0_SA_CA<3>
  VSS93  = GND
  CA5_A  = M_G_CPU0_SA_CA<5>
  VSS94  = GND
  CK_T  = M_G_CPU0_CLK_DP<0>
  CK_C  = M_G_CPU0_CLK_DN<0>
  VSS95  = GND
  RFU4  = TP_CHG_CPU0_DIMM1_FRU_4
  CA1_B  = M_G_CPU0_SB_CA<1>
  VSS96  = GND
  CA3_B  = M_G_CPU0_SB_CA<3>
  VSS97  = GND
  CA5_B  = M_G_CPU0_SB_CA<5>
  VSS98  = GND
  PAR_B  = M_G_CPU0_SB_PAR
  VSS99  = GND
  CS1_B_N  = M_G_CPU0_SB_CS_N<1>
  VSS100  = GND
  RFU5  = TP_CHG_CPU0_DIMM1_FRU_5
  RFU6  = TP_CHG_CPU0_DIMM1_FRU_6
  VSS101  = GND
  CB6_B  = M_G_CPU0_SB_CB<6>
  VSS102  = GND
  CB7_B  = M_G_CPU0_SB_CB<7>
  VSS103  = GND
  DQS4_B_C  = M_G_CPU0_SB_DQS_DN<4>
  DQS4_B_T  = M_G_CPU0_SB_DQS_DP<4>
  VSS104  = GND
  CB2_B  = M_G_CPU0_SB_CB<2>
  VSS105  = GND
  CB3_B  = M_G_CPU0_SB_CB<3>
  VSS106  = GND
  DQ2_B  = M_G_CPU0_SB_DQ<2>
  VSS107  = GND
  DQ3_B  = M_G_CPU0_SB_DQ<3>
  VSS108  = GND
  \dqs5_b_c||tdqs5_b_c\  = M_G_CPU0_SB_DQS_DN<5>
  \dqs5_b_t||tdqs5_b_t\  = M_G_CPU0_SB_DQS_DP<5>
  VSS109  = GND
  DQ6_B  = M_G_CPU0_SB_DQ<6>
  VSS110  = GND
  DQ7_B  = M_G_CPU0_SB_DQ<7>
  VSS111  = GND
  DQ10_B  = M_G_CPU0_SB_DQ<10>
  VSS112  = GND
  DQ11_B  = M_G_CPU0_SB_DQ<11>
  VSS113  = GND
  \dqs6_b_c||tdqs6_b_c\  = M_G_CPU0_SB_DQS_DN<6>
  \dqs6_b_t||tdqs6_b_t\  = M_G_CPU0_SB_DQS_DP<6>
  VSS114  = GND
  DQ14_B  = M_G_CPU0_SB_DQ<14>
  VSS115  = GND
  DQ15_B  = M_G_CPU0_SB_DQ<15>
  VSS116  = GND
  DQ18_B  = M_G_CPU0_SB_DQ<18>
  VSS117  = GND
  DQ19_B  = M_G_CPU0_SB_DQ<19>
  VSS118  = GND
  \dqs7_b_c||tdqs7_b_c\  = M_G_CPU0_SB_DQS_DN<7>
  \dqs7_b_t||tdqs7_b_t\  = M_G_CPU0_SB_DQS_DP<7>
  VSS119  = GND
  DQ22_B  = M_G_CPU0_SB_DQ<22>
  VSS120  = GND
  DQ23_B  = M_G_CPU0_SB_DQ<23>
  VSS121  = GND
  DQ26_B  = M_G_CPU0_SB_DQ<26>
  VSS122  = GND
  DQ27_B  = M_G_CPU0_SB_DQ<27>
  VSS123  = GND
  \dqs8_b_c||tdqs8_b_c\  = M_G_CPU0_SB_DQS_DN<8>
  \dqs8_b_t||tdqs8_b_t\  = M_G_CPU0_SB_DQS_DP<8>
  VSS124  = GND
  DQ30_B  = M_G_CPU0_SB_DQ<30>
  VSS125  = GND
  DQ31_B  = M_G_CPU0_SB_DQ<31>
  VSS126  = GND
  G1  = GND
  G2  = GND
  G3  = GND

(kicad_pcb
	(version 20260206)
	(generator "pcbnew")
	(generator_version "10.0")
	(general
		(thickness 1.6)
		(legacy_teardrops no)
	)
	(paper "A4")
	(title_block
		(title "03242023_DA0F0TMBIJ0_F0T_Motherboard_J_brd_V01_OCP.brd")
		(comment 1 "Grand Teton / footprint 1368 of 6105 (J13), pads 46-91 of 291")
	)
	(layers
		(0 "F.Cu" signal "TOP")
		(4 "In1.Cu" signal "GND")
		(6 "In2.Cu" signal "IN1")
		(8 "In3.Cu" signal "GND1")
		(10 "In4.Cu" signal "IN2")
		(12 "In5.Cu" signal "GND2")
		(14 "In6.Cu" signal "IN3")
		(16 "In7.Cu" signal "GND3")
		(18 "In8.Cu" signal "VCC")
		(20 "In9.Cu" signal "VCC1")
		(22 "In10.Cu" signal "GND4")
		(24 "In11.Cu" signal "IN4")
		(26 "In12.Cu" signal "GND5")
		(28 "In13.Cu" signal "IN5")
		(30 "In14.Cu" signal "GND6")
		(32 "In15.Cu" signal "IN6")
		(34 "In16.Cu" signal "GND7")
		(2 "B.Cu" signal "BOTTOM")
		(9 "F.Adhes" user "F.Adhesive")
		(11 "B.Adhes" user "B.Adhesive")
		(13 "F.Paste" user "Package Geometry/Pastemask Top")
		(15 "B.Paste" user "Package Geometry/Pastemask Bottom")
		(5 "F.SilkS" user "Ref Des/Silkscreen Top")
		(7 "B.SilkS" user "Ref Des/Silkscreen Bottom")
		(1 "F.Mask" user "Board Geometry/Soldermask Top")
		(3 "B.Mask" user "Board Geometry/Soldermask Bottom")
		(17 "Dwgs.User" user "User.Drawings")
		(19 "Cmts.User" user "User.Comments")
		(21 "Eco1.User" user "User.Eco1")
		(23 "Eco2.User" user "User.Eco2")
		(25 "Edge.Cuts" user "Board Geometry/Outline")
		(27 "Margin" user)
		(31 "F.CrtYd" user "Package Geometry/Place Bound Top")
		(29 "B.CrtYd" user "Package Geometry/Place Bound Bottom")
		(35 "F.Fab" user "Ref Des/Assembly Top")
		(33 "B.Fab" user "Ref Des/Assembly Bottom")
	)
	(footprint ""
		(layer "F.Cu")
		(at 446.522348 -258.091686)
		(property "Reference" "J13"
			(at -3.683 -81.702148 0)
			(unlocked yes)
			(layer "F.SilkS")
			(effects
				(font
					(size 0.7874 0.5842)
					(thickness 0.1524)
				)
				(justify left)
			)
		)
		(property "Value" ""
			(at 0 0 0)
			(layer "F.Fab")
			(effects
				(font
					(size 1.27 1.27)
				)
			)
		)
		(duplicate_pad_numbers_are_jumpers no)
		(pad "46" smd rect
			(at -2.050034 -25.07488 270)
			(size 0.519938 1.4986)
			(layers "F.Cu" "F.Mask" "F.Paste")
			(net "GND")
		)
		(pad "47" smd rect
			(at -2.050034 -24.224996 270)
			(size 0.519938 1.4986)
			(layers "F.Cu" "F.Mask" "F.Paste")
			(net "M_G_CPU0_SA_DQ<28>")
		)
		(pad "48" smd rect
			(at -2.050034 -23.375112 270)
			(size 0.519938 1.4986)
			(layers "F.Cu" "F.Mask" "F.Paste")
			(net "GND")
		)
		(pad "49" smd rect
			(at -2.050034 -22.524974 270)
			(size 0.519938 1.4986)
			(layers "F.Cu" "F.Mask" "F.Paste")
			(net "M_G_CPU0_SA_DQ<29>")
		)
		(pad "50" smd rect
			(at -2.050034 -21.67509 270)
			(size 0.519938 1.4986)
			(layers "F.Cu" "F.Mask" "F.Paste")
			(net "GND")
		)
		(pad "51" smd rect
			(at -2.050034 -20.824952 270)
			(size 0.519938 1.4986)
			(layers "F.Cu" "F.Mask" "F.Paste")
			(net "M_G_CPU0_SA_CB<0>")
		)
		(pad "52" smd rect
			(at -2.050034 -19.975068 270)
			(size 0.519938 1.4986)
			(layers "F.Cu" "F.Mask" "F.Paste")
			(net "GND")
		)
		(pad "53" smd rect
			(at -2.050034 -19.12493 270)
			(size 0.519938 1.4986)
			(layers "F.Cu" "F.Mask" "F.Paste")
			(net "M_G_CPU0_SA_CB<1>")
		)
		(pad "54" smd rect
			(at -2.050034 -18.275046 270)
			(size 0.519938 1.4986)
			(layers "F.Cu" "F.Mask" "F.Paste")
			(net "GND")
		)
		(pad "55" smd rect
			(at -2.050034 -17.424908 270)
			(size 0.519938 1.4986)
			(layers "F.Cu" "F.Mask" "F.Paste")
			(net "M_G_CPU0_SA_DQS_DP<4>")
		)
		(pad "56" smd rect
			(at -2.050034 -16.575024 270)
			(size 0.519938 1.4986)
			(layers "F.Cu" "F.Mask" "F.Paste")
			(net "M_G_CPU0_SA_DQS_DN<4>")
		)
		(pad "57" smd rect
			(at -2.050034 -15.724886 270)
			(size 0.519938 1.4986)
			(layers "F.Cu" "F.Mask" "F.Paste")
			(net "GND")
		)
		(pad "58" smd rect
			(at -2.050034 -14.875002 270)
			(size 0.519938 1.4986)
			(layers "F.Cu" "F.Mask" "F.Paste")
			(net "M_G_CPU0_SA_CB<4>")
		)
		(pad "59" smd rect
			(at -2.050034 -14.025118 270)
			(size 0.519938 1.4986)
			(layers "F.Cu" "F.Mask" "F.Paste")
			(net "GND")
		)
		(pad "60" smd rect
			(at -2.050034 -13.17498 270)
			(size 0.519938 1.4986)
			(layers "F.Cu" "F.Mask" "F.Paste")
			(net "M_G_CPU0_SA_CB<5>")
		)
		(pad "61" smd rect
			(at -2.050034 -12.325096 270)
			(size 0.519938 1.4986)
			(layers "F.Cu" "F.Mask" "F.Paste")
			(net "GND")
		)
		(pad "62" smd rect
			(at -2.050034 -11.474958 270)
			(size 0.519938 1.4986)
			(layers "F.Cu" "F.Mask" "F.Paste")
			(net "M_G_CPU0_ALERT_N")
		)
		(pad "63" smd rect
			(at -2.050034 -10.625074 270)
			(size 0.519938 1.4986)
			(layers "F.Cu" "F.Mask" "F.Paste")
			(net "GND")
		)
		(pad "64" smd rect
			(at -2.050034 -9.774936 270)
			(size 0.519938 1.4986)
			(layers "F.Cu" "F.Mask" "F.Paste")
			(net "M_G_CPU0_SA_CS_N<0>")
		)
		(pad "65" smd rect
			(at -2.050034 -8.925052 270)
			(size 0.519938 1.4986)
			(layers "F.Cu" "F.Mask" "F.Paste")
			(net "GND")
		)
		(pad "66" smd rect
			(at -2.050034 -8.074914 270)
			(size 0.519938 1.4986)
			(layers "F.Cu" "F.Mask" "F.Paste")
			(net "M_G_CPU0_SA_CA<0>")
		)
		(pad "67" smd rect
			(at -2.050034 -7.22503 270)
			(size 0.519938 1.4986)
			(layers "F.Cu" "F.Mask" "F.Paste")
			(net "GND")
		)
		(pad "68" smd rect
			(at -2.050034 -6.374892 270)
			(size 0.519938 1.4986)
			(layers "F.Cu" "F.Mask" "F.Paste")
			(net "M_G_CPU0_SA_CA<2>")
		)
		(pad "69" smd rect
			(at -2.050034 -5.525008 270)
			(size 0.519938 1.4986)
			(layers "F.Cu" "F.Mask" "F.Paste")
			(net "GND")
		)
		(pad "70" smd rect
			(at -2.050034 -4.675124 270)
			(size 0.519938 1.4986)
			(layers "F.Cu" "F.Mask" "F.Paste")
			(net "M_G_CPU0_SA_CA<4>")
		)
		(pad "71" smd rect
			(at -2.050034 -3.824986 270)
			(size 0.519938 1.4986)
			(layers "F.Cu" "F.Mask" "F.Paste")
			(net "GND")
		)
		(pad "72" smd rect
			(at -2.050034 -2.975102 270)
			(size 0.519938 1.4986)
			(layers "F.Cu" "F.Mask" "F.Paste")
			(net "M_G_CPU0_SA_CA<6>")
		)
		(pad "73" smd rect
			(at -2.050034 -2.124964 270)
			(size 0.519938 1.4986)
			(layers "F.Cu" "F.Mask" "F.Paste")
			(net "GND")
		)
		(pad "74" smd rect
			(at -2.050034 -1.27508 270)
			(size 0.519938 1.4986)
			(layers "F.Cu" "F.Mask" "F.Paste")
			(net "M_G_CPU0_SA_PAR")
		)
		(pad "75" smd rect
			(at -2.050034 -0.424942 270)
			(size 0.519938 1.4986)
			(layers "F.Cu" "F.Mask" "F.Paste")
			(net "GND")
		)
		(pad "76" smd rect
			(at -2.050034 5.525008 270)
			(size 0.519938 1.4986)
			(layers "F.Cu" "F.Mask" "F.Paste")
			(net "M_G_CPU0_SB_CA<0>")
		)
		(pad "77" smd rect
			(at -2.050034 6.374892 270)
			(size 0.519938 1.4986)
			(layers "F.Cu" "F.Mask" "F.Paste")
			(net "GND")
		)
		(pad "78" smd rect
			(at -2.050034 7.22503 270)
			(size 0.519938 1.4986)
			(layers "F.Cu" "F.Mask" "F.Paste")
			(net "M_G_CPU0_SB_CA<2>")
		)
		(pad "79" smd rect
			(at -2.050034 8.074914 270)
			(size 0.519938 1.4986)
			(layers "F.Cu" "F.Mask" "F.Paste")
			(net "GND")
		)
		(pad "80" smd rect
			(at -2.050034 8.925052 270)
			(size 0.519938 1.4986)
			(layers "F.Cu" "F.Mask" "F.Paste")
			(net "M_G_CPU0_SB_CA<4>")
		)
		(pad "81" smd rect
			(at -2.050034 9.774936 270)
			(size 0.519938 1.4986)
			(layers "F.Cu" "F.Mask" "F.Paste")
			(net "GND")
		)
		(pad "82" smd rect
			(at -2.050034 10.625074 270)
			(size 0.519938 1.4986)
			(layers "F.Cu" "F.Mask" "F.Paste")
			(net "M_G_CPU0_SB_CA<6>")
		)
		(pad "83" smd rect
			(at -2.050034 11.474958 270)
			(size 0.519938 1.4986)
			(layers "F.Cu" "F.Mask" "F.Paste")
			(net "GND")
		)
		(pad "84" smd rect
			(at -2.050034 12.325096 270)
			(size 0.519938 1.4986)
			(layers "F.Cu" "F.Mask" "F.Paste")
			(net "M_G_CPU0_SB_CS_N<0>")
		)
		(pad "85" smd rect
			(at -2.050034 13.17498 270)
			(size 0.519938 1.4986)
			(layers "F.Cu" "F.Mask" "F.Paste")
			(net "GND")
		)
		(pad "86" smd rect
			(at -2.050034 14.025118 270)
			(size 0.519938 1.4986)
			(layers "F.Cu" "F.Mask" "F.Paste")
			(net "M_G_CPU0_SA_RSP<0>")
		)
		(pad "87" smd rect
			(at -2.050034 14.875002 270)
			(size 0.519938 1.4986)
			(layers "F.Cu" "F.Mask" "F.Paste")
			(net "M_G_CPU0_SB_RSP<0>")
		)
		(pad "88" smd rect
			(at -2.050034 15.724886 270)
			(size 0.519938 1.4986)
			(layers "F.Cu" "F.Mask" "F.Paste")
			(net "GND")
		)
		(pad "89" smd rect
			(at -2.050034 16.575024 270)
			(size 0.519938 1.4986)
			(layers "F.Cu" "F.Mask" "F.Paste")
			(net "M_G_CPU0_SB_CB<4>")
		)
		(pad "90" smd rect
			(at -2.050034 17.424908 270)
			(size 0.519938 1.4986)
			(layers "F.Cu" "F.Mask" "F.Paste")
			(net "GND")
		)
		(pad "91" smd rect
			(at -2.050034 18.275046 270)
			(size 0.519938 1.4986)
			(layers "F.Cu" "F.Mask" "F.Paste")
			(net "M_G_CPU0_SB_CB<5>")
		)
	)
)
